(kicad_pcb
	(version 20260206)
	(generator "pcbnew")
	(generator_version "10.0")
	(general
		(thickness 1.6)
		(legacy_teardrops no)
	)
	(paper "A4")
	(title_block
		(title "baseboard — 13948-1b.1110WZS1818.brd")
		(comment 1 "Honey Badger (Wiwynn) / footprints 2432-2438 of 2523")
	)
	(layers
		(0 "F.Cu" signal "TOP")
		(4 "In1.Cu" signal "L2GND")
		(6 "In2.Cu" signal "L3")
		(8 "In3.Cu" signal "L4VCC")
		(10 "In4.Cu" signal "L5VCC")
		(12 "In5.Cu" signal "L6")
		(14 "In6.Cu" signal "L7GND")
		(2 "B.Cu" signal "BOTTOM")
		(9 "F.Adhes" user "F.Adhesive")
		(11 "B.Adhes" user "B.Adhesive")
		(13 "F.Paste" user "Package Geometry/Pastemask Top")
		(15 "B.Paste" user "Package Geometry/Pastemask Bottom")
		(5 "F.SilkS" user "Ref Des/Silkscreen Top")
		(7 "B.SilkS" user "Ref Des/Silkscreen Bottom")
		(1 "F.Mask" user "Board Geometry/Soldermask Top")
		(3 "B.Mask" user "Board Geometry/Soldermask Bottom")
		(17 "Dwgs.User" user "User.Drawings")
		(19 "Cmts.User" user "User.Comments")
		(21 "Eco1.User" user "User.Eco1")
		(23 "Eco2.User" user "User.Eco2")
		(25 "Edge.Cuts" user "Board Geometry/Outline")
		(27 "Margin" user)
		(31 "F.CrtYd" user "Package Geometry/Place Bound Top")
		(29 "B.CrtYd" user "Package Geometry/Place Bound Bottom")
		(35 "F.Fab" user "Ref Des/Assembly Top")
		(33 "B.Fab" user "Ref Des/Assembly Bottom")
	)
	(footprint ""
		(layer "B.Cu")
		(at 100.057966 -56.642 180)
		(property "Reference" "SR642"
			(at 0 0 0)
			(layer "B.SilkS")
			(hide yes)
			(effects
				(font
					(size 1.27 1.27)
				)
				(justify mirror)
			)
		)
		(property "Value" "10KR2F-2-GP"
			(at -0.064008 -3.993896 180)
			(unlocked yes)
			(layer "B.Fab")
			(hide yes)
			(effects
				(font
					(size 1.016 1.016)
					(thickness 0.1524)
				)
				(justify mirror)
			)
		)
		(property "Device Type" "R402H16"
			(at -0.064008 -5.517896 180)
			(unlocked yes)
			(layer "B.Fab")
			(hide yes)
			(effects
				(font
					(size 1.016 1.016)
					(thickness 0.1524)
				)
				(justify mirror)
			)
		)
		(duplicate_pad_numbers_are_jumpers no)
		(fp_line
			(start 0.508 -0.9398)
			(end 0.508 0.9398)
			(stroke
				(width 0.1524)
				(type default)
			)
			(layer "B.SilkS")
		)
		(fp_line
			(start -0.508 -0.9398)
			(end 0.508 -0.9398)
			(stroke
				(width 0.1524)
				(type default)
			)
			(layer "B.SilkS")
		)
		(fp_rect
			(start 0.508 0.9398)
			(end -0.508 -0.9398)
			(stroke
				(width 0)
				(type default)
			)
			(fill no)
			(layer "B.CrtYd")
		)
		(fp_rect
			(start 0.508 0.9398)
			(end -0.508 -0.9398)
			(stroke
				(width 0)
				(type default)
			)
			(fill no)
			(layer "B.Fab")
		)
		(pad "1" smd custom
			(at 0 -0.4445)
			(size 0.1397 0.1397)
			(layers "B.Cu" "B.Mask" "B.Paste")
			(net "P1V8_C")
			(options
				(clearance outline)
				(anchor circle)
			)
			(primitives
				(gr_poly
					(pts
						(arc
							(start -0.1778 0.2794)
							(mid -0.249642 0.249642)
							(end -0.2794 0.1778)
						)
						(arc
							(start -0.2794 -0.1778)
							(mid -0.249642 -0.249642)
							(end -0.1778 -0.2794)
						)
						(arc
							(start 0.1778 -0.2794)
							(mid 0.249642 -0.249642)
							(end 0.2794 -0.1778)
						)
						(arc
							(start 0.2794 0.1778)
							(mid 0.249642 0.249642)
							(end 0.1778 0.2794)
						)
					)
					(width 0)
					(fill yes)
				)
			)
		)
		(pad "2" smd custom
			(at 0 0.4445)
			(size 0.1397 0.1397)
			(layers "B.Cu" "B.Mask" "B.Paste")
			(net "AVSO_IDDTN18")
			(options
				(clearance outline)
				(anchor circle)
			)
			(primitives
				(gr_poly
					(pts
						(arc
							(start -0.1778 0.2794)
							(mid -0.249642 0.249642)
							(end -0.2794 0.1778)
						)
						(arc
							(start -0.2794 -0.1778)
							(mid -0.249642 -0.249642)
							(end -0.1778 -0.2794)
						)
						(arc
							(start 0.1778 -0.2794)
							(mid 0.249642 -0.249642)
							(end 0.2794 -0.1778)
						)
						(arc
							(start 0.2794 0.1778)
							(mid 0.249642 0.249642)
							(end 0.1778 0.2794)
						)
					)
					(width 0)
					(fill yes)
				)
			)
		)
	)
	(footprint ""
		(layer "B.Cu")
		(at 308.102 -160.655 180)
		(property "Reference" "R462"
			(at 0 0 0)
			(layer "B.SilkS")
			(hide yes)
			(effects
				(font
					(size 1.27 1.27)
				)
				(justify mirror)
			)
		)
		(property "Value" "0R2J-2-GP"
			(at -0.064008 -3.993896 180)
			(unlocked yes)
			(layer "B.Fab")
			(hide yes)
			(effects
				(font
					(size 1.016 1.016)
					(thickness 0.1524)
				)
				(justify mirror)
			)
		)
		(property "Device Type" "R402H16"
			(at -0.064008 -5.517896 180)
			(unlocked yes)
			(layer "B.Fab")
			(hide yes)
			(effects
				(font
					(size 1.016 1.016)
					(thickness 0.1524)
				)
				(justify mirror)
			)
		)
		(duplicate_pad_numbers_are_jumpers no)
		(fp_line
			(start 0.508 -0.9398)
			(end 0.508 0.9398)
			(stroke
				(width 0.1524)
				(type default)
			)
			(layer "B.SilkS")
		)
		(fp_line
			(start -0.508 -0.9398)
			(end 0.508 -0.9398)
			(stroke
				(width 0.1524)
				(type default)
			)
			(layer "B.SilkS")
		)
		(fp_rect
			(start 0.508 0.9398)
			(end -0.508 -0.9398)
			(stroke
				(width 0)
				(type default)
			)
			(fill no)
			(layer "B.CrtYd")
		)
		(fp_rect
			(start 0.508 0.9398)
			(end -0.508 -0.9398)
			(stroke
				(width 0)
				(type default)
			)
			(fill no)
			(layer "B.Fab")
		)
		(pad "1" smd custom
			(at 0 -0.4445)
			(size 0.1397 0.1397)
			(layers "B.Cu" "B.Mask" "B.Paste")
			(net "BMC_I2C_SDA_9")
			(options
				(clearance outline)
				(anchor circle)
			)
			(primitives
				(gr_poly
					(pts
						(arc
							(start -0.1778 0.2794)
							(mid -0.249642 0.249642)
							(end -0.2794 0.1778)
						)
						(arc
							(start -0.2794 -0.1778)
							(mid -0.249642 -0.249642)
							(end -0.1778 -0.2794)
						)
						(arc
							(start 0.1778 -0.2794)
							(mid 0.249642 -0.249642)
							(end 0.2794 -0.1778)
						)
						(arc
							(start 0.2794 0.1778)
							(mid 0.249642 0.249642)
							(end 0.1778 0.2794)
						)
					)
					(width 0)
					(fill yes)
				)
			)
		)
		(pad "2" smd custom
			(at 0 0.4445)
			(size 0.1397 0.1397)
			(layers "B.Cu" "B.Mask" "B.Paste")
			(net "BMC0_SMB9_DAT")
			(options
				(clearance outline)
				(anchor circle)
			)
			(primitives
				(gr_poly
					(pts
						(arc
							(start -0.1778 0.2794)
							(mid -0.249642 0.249642)
							(end -0.2794 0.1778)
						)
						(arc
							(start -0.2794 -0.1778)
							(mid -0.249642 -0.249642)
							(end -0.1778 -0.2794)
						)
						(arc
							(start 0.1778 -0.2794)
							(mid 0.249642 -0.249642)
							(end 0.2794 -0.1778)
						)
						(arc
							(start 0.2794 0.1778)
							(mid 0.249642 0.249642)
							(end 0.1778 0.2794)
						)
					)
					(width 0)
					(fill yes)
				)
			)
		)
	)
	(footprint ""
		(layer "B.Cu")
		(at 117.037612 -221.996)
		(property "Reference" "SR889"
			(at 0 0 0)
			(layer "B.SilkS")
			(hide yes)
			(effects
				(font
					(size 1.27 1.27)
				)
				(justify mirror)
			)
		)
		(property "Value" "0R2J-2-GP"
			(at -0.064008 -3.993896 0)
			(unlocked yes)
			(layer "B.Fab")
			(hide yes)
			(effects
				(font
					(size 1.016 1.016)
					(thickness 0.1524)
				)
				(justify mirror)
			)
		)
		(property "Device Type" "R402H16"
			(at -0.064008 -5.517896 0)
			(unlocked yes)
			(layer "B.Fab")
			(hide yes)
			(effects
				(font
					(size 1.016 1.016)
					(thickness 0.1524)
				)
				(justify mirror)
			)
		)
		(duplicate_pad_numbers_are_jumpers no)
		(fp_line
			(start -0.508 -0.9398)
			(end 0.508 -0.9398)
			(stroke
				(width 0.1524)
				(type default)
			)
			(layer "B.SilkS")
		)
		(fp_line
			(start 0.508 -0.9398)
			(end 0.508 0.9398)
			(stroke
				(width 0.1524)
				(type default)
			)
			(layer "B.SilkS")
		)
		(fp_rect
			(start 0.508 0.9398)
			(end -0.508 -0.9398)
			(stroke
				(width 0)
				(type default)
			)
			(fill no)
			(layer "B.CrtYd")
		)
		(fp_rect
			(start 0.508 0.9398)
			(end -0.508 -0.9398)
			(stroke
				(width 0)
				(type default)
			)
			(fill no)
			(layer "B.Fab")
		)
		(pad "1" smd custom
			(at 0 -0.4445 180)
			(size 0.1397 0.1397)
			(layers "B.Cu" "B.Mask" "B.Paste")
			(net "SAS_GF_EXP_RX_DN7")
			(options
				(clearance outline)
				(anchor circle)
			)
			(primitives
				(gr_poly
					(pts
						(arc
							(start -0.1778 0.2794)
							(mid -0.249642 0.249642)
							(end -0.2794 0.1778)
						)
						(arc
							(start -0.2794 -0.1778)
							(mid -0.249642 -0.249642)
							(end -0.1778 -0.2794)
						)
						(arc
							(start 0.1778 -0.2794)
							(mid 0.249642 -0.249642)
							(end 0.2794 -0.1778)
						)
						(arc
							(start 0.2794 0.1778)
							(mid 0.249642 0.249642)
							(end 0.1778 0.2794)
						)
					)
					(width 0)
					(fill yes)
				)
			)
		)
		(pad "2" smd custom
			(at 0 0.4445 180)
			(size 0.1397 0.1397)
			(layers "B.Cu" "B.Mask" "B.Paste")
			(net "SAS_HDD_CONN_SER_RX7_N")
			(options
				(clearance outline)
				(anchor circle)
			)
			(primitives
				(gr_poly
					(pts
						(arc
							(start -0.1778 0.2794)
							(mid -0.249642 0.249642)
							(end -0.2794 0.1778)
						)
						(arc
							(start -0.2794 -0.1778)
							(mid -0.249642 -0.249642)
							(end -0.1778 -0.2794)
						)
						(arc
							(start 0.1778 -0.2794)
							(mid 0.249642 -0.249642)
							(end 0.2794 -0.1778)
						)
						(arc
							(start 0.2794 0.1778)
							(mid 0.249642 0.249642)
							(end 0.1778 0.2794)
						)
					)
					(width 0)
					(fill yes)
				)
			)
		)
	)
	(footprint ""
		(layer "B.Cu")
		(at 102.49916 -31.623)
		(property "Reference" "SC873"
			(at 0 0 0)
			(layer "B.SilkS")
			(hide yes)
			(effects
				(font
					(size 1.27 1.27)
				)
				(justify mirror)
			)
		)
		(property "Value" "SCD22U6D3V1MX-1-GP"
			(at 2.8321 -1.7399 0)
			(unlocked yes)
			(layer "B.Fab")
			(hide yes)
			(effects
				(font
					(size 1.016 1.016)
					(thickness 0.1524)
				)
				(justify mirror)
			)
		)
		(property "Device Type" "C0201H13"
			(at 2.8321 -3.2639 0)
			(unlocked yes)
			(layer "B.Fab")
			(hide yes)
			(effects
				(font
					(size 1.016 1.016)
					(thickness 0.1524)
				)
				(justify mirror)
			)
		)
		(duplicate_pad_numbers_are_jumpers no)
		(fp_rect
			(start 0.2794 0.6477)
			(end -0.2794 -0.6477)
			(stroke
				(width 0)
				(type default)
			)
			(fill no)
			(layer "B.CrtYd")
		)
		(fp_rect
			(start 0.2794 0.6477)
			(end -0.2794 -0.6477)
			(stroke
				(width 0)
				(type default)
			)
			(fill no)
			(layer "B.Fab")
		)
		(pad "1" smd custom
			(at 0 -0.2794 180)
			(size 0.0762 0.0762)
			(layers "B.Cu" "B.Mask" "B.Paste")
			(net "PCIE_SAS_C_CPU_RX_P6")
			(options
				(clearance outline)
				(anchor circle)
			)
			(primitives
				(gr_poly
					(pts
						(arc
							(start 0.1524 0.127)
							(mid 0.137521 0.162921)
							(end 0.1016 0.1778)
						)
						(arc
							(start -0.1016 0.1778)
							(mid -0.137521 0.162921)
							(end -0.1524 0.127)
						)
						(arc
							(start -0.1524 -0.127)
							(mid -0.137521 -0.162921)
							(end -0.1016 -0.1778)
						)
						(arc
							(start 0.1016 -0.1778)
							(mid 0.137521 -0.162921)
							(end 0.1524 -0.127)
						)
					)
					(width 0)
					(fill yes)
				)
			)
		)
		(pad "2" smd custom
			(at 0 0.2794 180)
			(size 0.0762 0.0762)
			(layers "B.Cu" "B.Mask" "B.Paste")
			(net "PCIE_SAS_CPU_RX_P6")
			(options
				(clearance outline)
				(anchor circle)
			)
			(primitives
				(gr_poly
					(pts
						(arc
							(start 0.1524 0.127)
							(mid 0.137521 0.162921)
							(end 0.1016 0.1778)
						)
						(arc
							(start -0.1016 0.1778)
							(mid -0.137521 0.162921)
							(end -0.1524 0.127)
						)
						(arc
							(start -0.1524 -0.127)
							(mid -0.137521 -0.162921)
							(end -0.1016 -0.1778)
						)
						(arc
							(start 0.1016 -0.1778)
							(mid 0.137521 -0.162921)
							(end 0.1524 -0.127)
						)
					)
					(width 0)
					(fill yes)
				)
			)
		)
	)
	(footprint ""
		(layer "B.Cu")
		(at 111.614966 -28.829 90)
		(property "Reference" "SR656"
			(at 0 0 90)
			(layer "B.SilkS")
			(hide yes)
			(effects
				(font
					(size 1.27 1.27)
				)
				(justify mirror)
			)
		)
		(property "Value" "0R2J-2-GP"
			(at -0.064008 -3.993896 90)
			(unlocked yes)
			(layer "B.Fab")
			(hide yes)
			(effects
				(font
					(size 1.016 1.016)
					(thickness 0.1524)
				)
				(justify mirror)
			)
		)
		(property "Device Type" "R402H16"
			(at -0.064008 -5.517896 90)
			(unlocked yes)
			(layer "B.Fab")
			(hide yes)
			(effects
				(font
					(size 1.016 1.016)
					(thickness 0.1524)
				)
				(justify mirror)
			)
		)
		(duplicate_pad_numbers_are_jumpers no)
		(fp_line
			(start 0.508 -0.9398)
			(end 0.508 0.9398)
			(stroke
				(width 0.1524)
				(type default)
			)
			(layer "B.SilkS")
		)
		(fp_line
			(start -0.508 -0.9398)
			(end 0.508 -0.9398)
			(stroke
				(width 0.1524)
				(type default)
			)
			(layer "B.SilkS")
		)
		(fp_rect
			(start 0.508 0.9398)
			(end -0.508 -0.9398)
			(stroke
				(width 0)
				(type default)
			)
			(fill no)
			(layer "B.CrtYd")
		)
		(fp_rect
			(start 0.508 0.9398)
			(end -0.508 -0.9398)
			(stroke
				(width 0)
				(type default)
			)
			(fill no)
			(layer "B.Fab")
		)
		(pad "1" smd custom
			(at 0 -0.4445 270)
			(size 0.1397 0.1397)
			(layers "B.Cu" "B.Mask" "B.Paste")
			(net "SYS_RST_N_0")
			(options
				(clearance outline)
				(anchor circle)
			)
			(primitives
				(gr_poly
					(pts
						(arc
							(start -0.1778 0.2794)
							(mid -0.249642 0.249642)
							(end -0.2794 0.1778)
						)
						(arc
							(start -0.2794 -0.1778)
							(mid -0.249642 -0.249642)
							(end -0.1778 -0.2794)
						)
						(arc
							(start 0.1778 -0.2794)
							(mid 0.249642 -0.249642)
							(end 0.2794 -0.1778)
						)
						(arc
							(start 0.2794 0.1778)
							(mid 0.249642 0.249642)
							(end 0.1778 0.2794)
						)
					)
					(width 0)
					(fill yes)
				)
			)
		)
		(pad "2" smd custom
			(at 0 0.4445 270)
			(size 0.1397 0.1397)
			(layers "B.Cu" "B.Mask" "B.Paste")
			(net "SYS_RST")
			(options
				(clearance outline)
				(anchor circle)
			)
			(primitives
				(gr_poly
					(pts
						(arc
							(start -0.1778 0.2794)
							(mid -0.249642 0.249642)
							(end -0.2794 0.1778)
						)
						(arc
							(start -0.2794 -0.1778)
							(mid -0.249642 -0.249642)
							(end -0.1778 -0.2794)
						)
						(arc
							(start 0.1778 -0.2794)
							(mid 0.249642 -0.249642)
							(end 0.2794 -0.1778)
						)
						(arc
							(start 0.2794 0.1778)
							(mid 0.249642 0.249642)
							(end 0.1778 0.2794)
						)
					)
					(width 0)
					(fill yes)
				)
			)
		)
	)
	(footprint ""
		(layer "B.Cu")
		(at 124.403612 -212.344 90)
		(property "Reference" "SR910"
			(at 0 0 90)
			(layer "B.SilkS")
			(hide yes)
			(effects
				(font
					(size 1.27 1.27)
				)
				(justify mirror)
			)
		)
		(property "Value" "4K7R2F-GP"
			(at -0.064008 -3.993896 90)
			(unlocked yes)
			(layer "B.Fab")
			(hide yes)
			(effects
				(font
					(size 1.016 1.016)
					(thickness 0.1524)
				)
				(justify mirror)
			)
		)
		(property "Device Type" "R402H16"
			(at -0.064008 -5.517896 90)
			(unlocked yes)
			(layer "B.Fab")
			(hide yes)
			(effects
				(font
					(size 1.016 1.016)
					(thickness 0.1524)
				)
				(justify mirror)
			)
		)
		(duplicate_pad_numbers_are_jumpers no)
		(fp_line
			(start 0.508 -0.9398)
			(end 0.508 0.9398)
			(stroke
				(width 0.1524)
				(type default)
			)
			(layer "B.SilkS")
		)
		(fp_line
			(start -0.508 -0.9398)
			(end 0.508 -0.9398)
			(stroke
				(width 0.1524)
				(type default)
			)
			(layer "B.SilkS")
		)
		(fp_rect
			(start 0.508 0.9398)
			(end -0.508 -0.9398)
			(stroke
				(width 0)
				(type default)
			)
			(fill no)
			(layer "B.CrtYd")
		)
		(fp_rect
			(start 0.508 0.9398)
			(end -0.508 -0.9398)
			(stroke
				(width 0)
				(type default)
			)
			(fill no)
			(layer "B.Fab")
		)
		(pad "1" smd custom
			(at 0 -0.4445 270)
			(size 0.1397 0.1397)
			(layers "B.Cu" "B.Mask" "B.Paste")
			(net "REDV_I2C_SEL1A")
			(options
				(clearance outline)
				(anchor circle)
			)
			(primitives
				(gr_poly
					(pts
						(arc
							(start -0.1778 0.2794)
							(mid -0.249642 0.249642)
							(end -0.2794 0.1778)
						)
						(arc
							(start -0.2794 -0.1778)
							(mid -0.249642 -0.249642)
							(end -0.1778 -0.2794)
						)
						(arc
							(start 0.1778 -0.2794)
							(mid 0.249642 -0.249642)
							(end 0.2794 -0.1778)
						)
						(arc
							(start 0.2794 0.1778)
							(mid 0.249642 0.249642)
							(end 0.1778 0.2794)
						)
					)
					(width 0)
					(fill yes)
				)
			)
		)
		(pad "2" smd custom
			(at 0 0.4445 270)
			(size 0.1397 0.1397)
			(layers "B.Cu" "B.Mask" "B.Paste")
			(net "GND")
			(options
				(clearance outline)
				(anchor circle)
			)
			(primitives
				(gr_poly
					(pts
						(arc
							(start -0.1778 0.2794)
							(mid -0.249642 0.249642)
							(end -0.2794 0.1778)
						)
						(arc
							(start -0.2794 -0.1778)
							(mid -0.249642 -0.249642)
							(end -0.1778 -0.2794)
						)
						(arc
							(start 0.1778 -0.2794)
							(mid 0.249642 -0.249642)
							(end 0.2794 -0.1778)
						)
						(arc
							(start 0.2794 0.1778)
							(mid 0.249642 0.249642)
							(end 0.1778 0.2794)
						)
					)
					(width 0)
					(fill yes)
				)
			)
		)
	)
	(footprint ""
		(layer "B.Cu")
		(at 101.454966 -43.307 -90)
		(property "Reference" "SC1061"
			(at 0 0 90)
			(layer "B.SilkS")
			(hide yes)
			(effects
				(font
					(size 1.27 1.27)
				)
				(justify mirror)
			)
		)
		(property "Value" "SCD1U16V2KX-3GP"
			(at -1.1811 -2.7051 270)
			(unlocked yes)
			(layer "B.Fab")
			(hide yes)
			(effects
				(font
					(size 1.016 1.016)
					(thickness 0.1524)
				)
				(justify mirror)
			)
		)
		(property "Device Type" "C402H22"
			(at -1.1811 -4.2291 270)
			(unlocked yes)
			(layer "B.Fab")
			(hide yes)
			(effects
				(font
					(size 1.016 1.016)
					(thickness 0.1524)
				)
				(justify mirror)
			)
		)
		(duplicate_pad_numbers_are_jumpers no)
		(fp_rect
			(start 0.4318 0.9525)
			(end -0.4318 -0.9525)
			(stroke
				(width 0)
				(type default)
			)
			(fill no)
			(layer "B.CrtYd")
		)
		(fp_rect
			(start 0.4318 0.9525)
			(end -0.4318 -0.9525)
			(stroke
				(width 0)
				(type default)
			)
			(fill no)
			(layer "B.Fab")
		)
		(pad "1" smd custom
			(at 0 -0.4445 90)
			(size 0.1524 0.1524)
			(layers "B.Cu" "B.Mask" "B.Paste")
			(net "P0V955_C")
			(options
				(clearance outline)
				(anchor circle)
			)
			(primitives
				(gr_poly
					(pts
						(arc
							(start 0.3048 0.2032)
							(mid 0.275042 0.275042)
							(end 0.2032 0.3048)
						)
						(arc
							(start -0.2032 0.3048)
							(mid -0.275042 0.275042)
							(end -0.3048 0.2032)
						)
						(arc
							(start -0.3048 -0.2032)
							(mid -0.275042 -0.275042)
							(end -0.2032 -0.3048)
						)
						(arc
							(start 0.2032 -0.3048)
							(mid 0.275042 -0.275042)
							(end 0.3048 -0.2032)
						)
					)
					(width 0)
					(fill yes)
				)
			)
		)
		(pad "2" smd custom
			(at 0 0.4445 90)
			(size 0.1524 0.1524)
			(layers "B.Cu" "B.Mask" "B.Paste")
			(net "GND")
			(options
				(clearance outline)
				(anchor circle)
			)
			(primitives
				(gr_poly
					(pts
						(arc
							(start 0.3048 0.2032)
							(mid 0.275042 0.275042)
							(end 0.2032 0.3048)
						)
						(arc
							(start -0.2032 0.3048)
							(mid -0.275042 0.275042)
							(end -0.3048 0.2032)
						)
						(arc
							(start -0.3048 -0.2032)
							(mid -0.275042 -0.275042)
							(end -0.2032 -0.3048)
						)
						(arc
							(start 0.2032 -0.3048)
							(mid 0.275042 -0.275042)
							(end 0.3048 -0.2032)
						)
					)
					(width 0)
					(fill yes)
				)
			)
		)
	)
)
